FILE_TYPE = CONNECTIVITY;
{Allegro Design Entry HDL 17.2-2016 S081 (4005846) 1/11/2022}
"PAGE_NUMBER" = 34;
0"NC";
1"P3V3_AUX\g";
2"PVCCIO_AUX_PLD\g";
3"P3V3_AUX\g";
4"PVCCIO_AUX_PLD\g";
5"VCCIO0\g";
6"P3V3_AUX\g";
7"VCCIO2\g";
8"VCCIO0\g";
9"P3V3_AUX\g";
10"GND\g";
11"GND\g";
12"GND\g";
13"CLK_25M_OSC_FPGA_R";
14"IRQ_OC_DETECT_N";
15"IRQ_CPU1_VRHOT_N";
16"IRQ_CPU0_VRHOT_N";
17"PWRGD_CPUPWRGD_LVC1";
18"RST_EXTRST_R_N";
19"TP_PLD_19D";
20"IRQ_PCH_SCI_WHEA_N";
21"SMB_BMC_MM16_R5_SDA";
22"SMB_BMC_MM16_R5_SCL";
23"FM_CPU_MSMI_CATERR_LVT3_PLD_N";
24"FM_JTAG_BMC_MUX_SEL_R2";
25"RST_RSMRST_N";
26"RST_PCA9548_SENSOR_N";
27"BSM_PRSNT_R1_N";
28"IRQ_BMC_CPU_NMI_R";
29"PWRGD_PSU_AC_PWROK_PLD";
30"RST_PLTRST_R1_N";
31"IRQ_UV_DETECT_N";
32"RST_BMC_RSTBTN_OUT_N";
33"BMC_CPLD_GPIO_2_R2";
34"FM_ME_BT_DONE";
35"CLK_25M_OSC_FPGA";
36"IRQ_BMC_PCH_NMI_R_N";
37"JTAG_SCM_PLD_TMS";
38"JTAG_SCM_PLD_TCK";
39"FM_PCH_BMC_THERMTRIP_N";
40"H_CPU1_PROCHOT_LVC1_R_N";
41"PU_FPGA_NSTATUS";
42"FM_THERMTRIP_DLY_LVC1_R_N";
43"SGPIO_PLD_DI_0";
44"SGPIO_PLD_LD_0";
45"SGPIO_PLD_DO_0";
46"SGPIO_CLK_PLD_0";
47"IRQ_OC_DETECT_EN_N";
48"FM_ADR_COMPLETE";
49"PU_PT20D";
50"JTAG_SCM_PLD_R_JTAGEN";
51"FM_CPU_MSMI_CATERR_LVT3_N";
52"JTAG_SCM_PLD_JTAGEN";
53"RST_EXTRST_N";
54"SMB_BMC_MM16_R3_SCL";
55"RST_SRST_PLD_BMC_R2_N";
56"SMB_BMC_MM16_R3_SDA";
57"RST_SRST_PLD_BMC_R_N";
58"SGPIO_DI_0";
59"SGPIO_LD_0";
60"SGPIO_DO_0";
61"SGPIO_CLK_0";
62"PU_FPGA_CONFIG_DONE";
63"FM_PCIE_M2_SSD0_PRSNT_N";
64"FM_BIOS_POST_CMPLT_BMC_N";
65"FM_TPM_PRSNT_1_R_N";
66"FM_TPM_PRSNT_0_R_N";
67"FM_TPM_PRSNT_0_N";
68"FM_TPM_PRSNT_1_N";
69"FM_BMC_DBP_PRESENT_N";
70"BSM_PRSNT_R_N";
71"FM_JTAG_BMC_MUX_SEL";
72"PWRGD_PSU_AC_PWROK";
73"RST_PLTRST_N";
74"PWRGD_PCH_PWROK";
75"RST_RSMRST_N";
76"JTAG_SCM_PLD_TDO";
77"JTAG_SCM_PLD_TDI";
78"PU_25M_FPGA_CLK_EN";
79"IRQ_BMC_PCH_NMI_N";
80"CLK_25M_OSC_FPGA";
81"PU_FPGA_NSTATUS";
82"PU_FPGA_NCONFIG";
83"PU_FPGA_CONFIG_DONE";
84"BMC_CPLD_GPIO_2";
%"LCMXO3LF2100C5BG256C"
"1","(-4900,4100)","0","pure_quanta","I1";
;
VALUE"LCMXO3LF-2100C-5BG256C"
PART_TYPE"SMLF"
MATERIAL"IC"
PART_NUMBER"AJ021000T03"
CDS_LIB"pure_quanta"
CDS_LMAN_SYM_OUTLINE"-575,1250,575,-1250"
NEEDS_NO_SIZE"TRUE"
LOCATION"U25"
$SEC"1"
CDS_SEC"1";
"PT18A"
$PN"F8"55;
"PT24D||DONE"
$PN"C13"62;
"PT24C||INITN"
$PN"A13"41;
"PT24B"
$PN"A15"42;
"PT24A"
$PN"B14"43;
"PT23B"
$PN"B12"44;
"PT23A"
$PN"C12"45;
"PT22D"
$PN"A14"46;
"PT22C"
$PN"B13"47;
"PT22B"
$PN"A12"48;
"PT22A"
$PN"B11"14;
"PT21D"
$PN"D11"15;
"PT21C"
$PN"F10"16;
"PT21B"
$PN"C11"17;
"PT21A"
$PN"A11"18;
"PT20D||PROGRAMN"
$PN"B10"49;
"PT20C||JTAGENB"
$PN"C10"50;
"PT20B"
$PN"E10"23;
"PT20A"
$PN"D10"0;
"PT19D"
$PN"E11"19;
"PT19C"
$PN"F9"0;
"PT19B"
$PN"A10"0;
"PT19A"
$PN"B9"20;
"PT18D||SDA||PCLKC0_0"
$PN"C9"56;
"PT18C||SCL||PCLKT0_0"
$PN"A9"54;
"PT18B"
$PN"D9"0;
"PT17D"
$PN"E9"40;
"PT17C"
$PN"D8"39;
"PT17B||PCLKC0_1"
$PN"A8"36;
"PT17A||PCLKT0_1"
$PN"C8"35;
"PT16D||TMS"
$PN"B8"37;
"PT16C||TCK"
$PN"A7"38;
"PT16B"
$PN"E8"64;
"PT16A"
$PN"F7"63;
"PT13D"
$PN"D7"34;
"PT13C"
$PN"E6"33;
"PT13B"
$PN"C7"32;
"PT13A"
$PN"B7"31;
"PT12D||TDI"
$PN"A6"77;
"PT12C||TDO"
$PN"C6"76;
"PT12B"
$PN"E7"74;
"PT12A"
$PN"D6"69;
"PT11D"
$PN"B4"26;
"PT11C"
$PN"A3"27;
"PT11B"
$PN"B6"24;
"PT11A"
$PN"A5"25;
"PT10B"
$PN"C5"29;
"PT10A"
$PN"A4"30;
"PT9C"
$PN"B3"28;
"PT9B"
$PN"B5"65;
"PT9A"
$PN"C4"66;
"VCCIO0_G9"
$PN"G9"8;
"VCCIO0_G8"
$PN"G8"8;
"VCCIO0_D12"
$PN"D12"5;
"VCCIO0_D5"
$PN"D5"5;
%"Q_RES"
"1","(-6950,700)","0","pure_quanta","I115";
;
MATERIAL"CHIP"
VALUE"10K"
PART_NUMBER"CS31002FB08"
PACK_TYPE"0402LF"
TOLERANCE"1%"
WATTAGE"1/16W"
CDS_LIB"pure_quanta"
LOCATION"R809"
$SEC"1"
CDS_SEC"1";
"B"
$PN"2"4;
"A"
$PN"1"82;
%"Q_RES"
"1","(-6950,650)","0","pure_quanta","I116";
;
MATERIAL"CHIP"
VALUE"10K"
PART_NUMBER"CS31002FB08"
PACK_TYPE"0402LF"
TOLERANCE"1%"
WATTAGE"1/16W"
CDS_LIB"pure_quanta"
LOCATION"R810"
$SEC"1"
CDS_SEC"1";
"B"
$PN"2"4;
"A"
$PN"1"81;
%"Q_RES"
"1","(-6950,750)","0","pure_quanta","I117";
;
VALUE"10K"
MATERIAL"CHIP"
PART_NUMBER"CS31002FB08"
PACK_TYPE"0402LF"
TOLERANCE"1%"
WATTAGE"1/16W"
CDS_LIB"pure_quanta"
LOCATION"R808"
$SEC"1"
CDS_SEC"1";
"B"
$PN"2"4;
"A"
$PN"1"83;
%"UNIVERSAL_POWER"
"1","(-6400,925)","0","logical_power","I118";
;
HDL_POWER"PVCCIO_AUX_PLD"
CDS_LIB"logical_power";
"A"4;
%"Q_RES"
"2","(-4375,950)","0","pure_quanta","I119";
;
PACK_TYPE"0402LF"
MATERIAL"CHIP"
WATTAGE"1/16W"
TOLERANCE"1%"
VALUE"4.7K"
CDS_LIB"pure_quanta"
PART_NUMBER"CS24702FB06"
LOCATION"R806"
$SEC"1"
CDS_SEC"1";
"A"
$PN"1"3;
"B"
$PN"2"78;
%"UNIVERSAL_POWER"
"1","(-4375,1275)","0","logical_power","I120";
;
HDL_POWER"P3V3_AUX"
CDS_LIB"logical_power";
"A"3;
%"UNIVERSAL_GND"
"1","(-3975,825)","0","logical_power","I121";
;
HDL_POWER"GND"
CDS_LIB"logical_power";
"A"12;
%"Q_CAP"
"1","(-3975,1125)","0","pure_quanta","I122";
;
TOLERANCE"10%"
VOLTAGE"25V"
VALUE"0.1UF"
MATERIAL"X7R"
PACK_TYPE"0402"
CDS_LIB"pure_quanta"
PART_NUMBER"CH4104K1B00"
LOCATION"C318"
$SEC"1"
CDS_SEC"1";
"B"
$PN"2"12;
"A"
$PN"1"1;
%"UNIVERSAL_POWER"
"1","(-3975,1475)","0","logical_power","I123";
;
HDL_POWER"P3V3_AUX"
CDS_LIB"logical_power";
"A"1;
%"UNIVERSAL_GND"
"1","(-2725,500)","0","logical_power","I124";
;
HDL_POWER"GND"
CDS_LIB"logical_power";
"A"11;
%"Q_RES"
"1","(-1800,850)","0","pure_quanta","I126";
;
PACK_TYPE"0402LF"
WATTAGE"1/16W"
PART_NUMBER"CS03322FB03"
TOLERANCE"1%"
MATERIAL"CHIP"
VALUE"33.2"
CDS_LIB"pure_quanta"
LOCATION"R807"
$SEC"1"
CDS_SEC"1";
"B"
$PN"2"80;
"A"
$PN"1"13;
%"OSC4_7X25000018"
"1","(-3225,775)","0","pure_quanta","I127";
;
MATERIAL"MISC"
PART_NUMBER"BF625000023"
PART_TYPE"SMLF"
VALUE"25MHZ"
CDS_LMAN_SYM_OUTLINE"-175,125,175,-125"
PIN_NAMES_ROTATE"True"
CDS_LIB"pure_quanta"
LOCATION"OSC2"
$SEC"1"
CDS_SEC"1";
"VDD"
$PN"4"1;
"OUT"
$PN"3"13;
"GND"
$PN"2"11;
"OE"
$PN"1"78;
%"UNIVERSAL_POWER"
"1","(-3800,3200)","0","logical_power","I128";
;
HDL_POWER"VCCIO0"
CDS_LIB"logical_power";
"A"8;
%"UNIVERSAL_POWER"
"1","(-6000,3150)","0","logical_power","I129";
;
HDL_POWER"VCCIO0"
CDS_LIB"logical_power";
"A"5;
%"UNIVERSAL_POWER"
"1","(-600,4525)","0","logical_power","I136";
;
HDL_POWER"VCCIO2"
CDS_LIB"logical_power";
"A"7;
%"Q_RES"
"1","(-2550,4450)","0","pure_quanta","I137";
;
PART_NUMBER"CS31002FB08"
MATERIAL"CHIP"
VALUE"10K"
WATTAGE"1/16W"
PACK_TYPE"0402LF"
TOLERANCE"1%"
CDS_LIB"pure_quanta"
LOCATION"R297"
$SEC"1"
CDS_SEC"1";
"B"
$PN"2"7;
"A"
$PN"1"49;
%"UNIVERSAL_POWER"
"1","(-8400,2150)","0","logical_power","I138";
;
HDL_POWER"P3V3_AUX"
CDS_LIB"logical_power";
"A"6;
%"Q_RES"
"1","(-8200,1850)","0","pure_quanta","I139";
;
MATERIAL"CHIP"
TOLERANCE"5%"
PACK_TYPE"0402LF"
VALUE"0"
WATTAGE"1/16W"
PART_NUMBER"CS00002JB13"
CDS_LIB"pure_quanta"
$LOCATION"R183"
CDS_LOCATION"R183"
$SEC"1"
CDS_SEC"1";
"B"
$PN"2"2;
"A"
$PN"1"6;
%"Q_CAP"
"1","(-7375,1650)","0","pure_quanta","I140";
;
TOLERANCE"10%"
VALUE"1UF"
VOLTAGE"25V"
MATERIAL"X6S"
PACK_TYPE"C0402"
PART_NUMBER"CH5104KEB02"
CDS_LIB"pure_quanta"
$LOCATION"C256"
CDS_LOCATION"C256"
$SEC"1"
CDS_SEC"1";
"B"
$PN"2"10;
"A"
$PN"1"2;
%"UNIVERSAL_GND"
"1","(-6725,1200)","0","logical_power","I141";
;
ROOM"IO_SLOT"
HDL_POWER"GND"
CDS_LIB"logical_power";
"A"10;
%"UNIVERSAL_POWER"
"1","(-6350,1950)","0","logical_power","I143";
;
HDL_POWER"PVCCIO_AUX_PLD"
CDS_LIB"logical_power";
"A"2;
%"Q_CAP"
"1","(-6725,1625)","0","pure_quanta","I144";
;
VOLTAGE"25V"
PACK_TYPE"0402"
TOLERANCE"10%"
MATERIAL"X7R"
PART_NUMBER"CH4104K1B00"
VALUE"0.1UF"
CDS_LIB"pure_quanta"
$LOCATION"C257"
CDS_LOCATION"C257"
$SEC"1"
CDS_SEC"1";
"B"
$PN"2"10;
"A"
$PN"1"2;
%"Q_RES"
"1","(-7125,4000)","0","pure_quanta","I147";
;
MATERIAL"CHIP"
VALUE"0"
PACK_TYPE"0402LF"
WATTAGE"1/16W"
TOLERANCE"5%"
PART_NUMBER"CS00002JB13"
CDS_LIB"pure_quanta"
LOCATION"R519"
$SEC"1"
CDS_SEC"1";
"B"
$PN"2"33;
"A"
$PN"1"84;
%"Q_RES"
"1","(-7000,5200)","0","pure_quanta","I150";
;
VALUE"33.2"
MATERIAL"CHIP"
PACK_TYPE"0402LF"
WATTAGE"1/16W"
PART_NUMBER"CS03322FB03"
TOLERANCE"1%"
CDS_LIB"pure_quanta"
LOCATION"R767"
$SEC"1"
CDS_SEC"1";
"B"
$PN"2"66;
"A"
$PN"1"67;
%"Q_RES"
"1","(-2725,5250)","0","pure_quanta","I155";
;
MATERIAL"CHIP"
VALUE"0"
PART_NUMBER"CS00002JB13"
PACK_TYPE"0402LF"
WATTAGE"1/16W"
TOLERANCE"5%"
SEC_TYPE"0402LF"
CDS_LIB"pure_quanta"
$LOCATION"R10"
CDS_LOCATION"R10"
SEC"1";
"B"
$PN"2"57;
"A"
$PN"1"55;
%"Q_RES"
"1","(-7000,5150)","0","pure_quanta","I156";
;
VALUE"33.2"
MATERIAL"CHIP"
CDS_LIB"pure_quanta"
PACK_TYPE"0402LF"
WATTAGE"1/16W"
PART_NUMBER"CS03322FB03"
TOLERANCE"1%"
LOCATION"R123"
$SEC"1"
CDS_SEC"1";
"B"
$PN"2"65;
"A"
$PN"1"68;
%"Q_RES"
"1","(-7000,4950)","0","pure_quanta","I157";
;
MATERIAL"CHIP"
VALUE"33.2"
CDS_LIB"pure_quanta"
PACK_TYPE"0402LF"
WATTAGE"1/16W"
PART_NUMBER"CS03322FB03"
TOLERANCE"1%"
LOCATION"R718"
$SEC"1"
CDS_SEC"1";
"B"
$PN"2"30;
"A"
$PN"1"73;
%"Q_RES"
"1","(-7000,4900)","0","pure_quanta","I158";
;
VALUE"33.2"
MATERIAL"CHIP"
CDS_LIB"pure_quanta"
PACK_TYPE"0402LF"
WATTAGE"1/16W"
PART_NUMBER"CS03322FB03"
TOLERANCE"1%"
LOCATION"R837"
$SEC"1"
CDS_SEC"1";
"B"
$PN"2"29;
"A"
$PN"1"72;
%"Q_RES"
"1","(-7000,4650)","0","pure_quanta","I159";
;
MATERIAL"CHIP"
VALUE"33.2"
CDS_LIB"pure_quanta"
PACK_TYPE"0402LF"
WATTAGE"1/16W"
PART_NUMBER"CS03322FB03"
TOLERANCE"1%"
LOCATION"R459"
$SEC"1"
CDS_SEC"1";
"B"
$PN"2"27;
"A"
$PN"1"70;
%"Q_RES"
"1","(-2550,3850)","0","pure_quanta","I160";
;
VALUE"33.2"
MATERIAL"CHIP"
CDS_LIB"pure_quanta"
TOLERANCE"1%"
PART_NUMBER"CS03322FB03"
WATTAGE"1/16W"
PACK_TYPE"0402LF"
LOCATION"R434"
$SEC"1"
CDS_SEC"1";
"B"
$PN"2"61;
"A"
$PN"1"46;
%"Q_RES"
"1","(-2550,3750)","0","pure_quanta","I161";
;
MATERIAL"CHIP"
VALUE"33.2"
CDS_LIB"pure_quanta"
PACK_TYPE"0402LF"
WATTAGE"1/16W"
PART_NUMBER"CS03322FB03"
TOLERANCE"1%"
LOCATION"R435"
$SEC"1"
CDS_SEC"1";
"B"
$PN"2"60;
"A"
$PN"1"45;
%"Q_RES"
"1","(-2550,3700)","0","pure_quanta","I162";
;
MATERIAL"CHIP"
VALUE"33.2"
CDS_LIB"pure_quanta"
PACK_TYPE"0402LF"
WATTAGE"1/16W"
PART_NUMBER"CS03322FB03"
TOLERANCE"1%"
LOCATION"R436"
$SEC"1"
CDS_SEC"1";
"B"
$PN"2"59;
"A"
$PN"1"44;
%"Q_RES"
"1","(-2550,3600)","0","pure_quanta","I163";
;
MATERIAL"CHIP"
VALUE"33.2"
CDS_LIB"pure_quanta"
PACK_TYPE"0402LF"
WATTAGE"1/16W"
PART_NUMBER"CS03322FB03"
TOLERANCE"1%"
LOCATION"R437"
$SEC"1"
CDS_SEC"1";
"B"
$PN"2"58;
"A"
$PN"1"43;
%"Q_RES"
"1","(-2550,4600)","0","pure_quanta","I164";
;
MATERIAL"CHIP"
VALUE"33.2"
CDS_LIB"pure_quanta"
PACK_TYPE"0402LF"
WATTAGE"1/16W"
PART_NUMBER"CS03322FB03"
TOLERANCE"1%"
LOCATION"R270"
$SEC"1"
CDS_SEC"1";
"B"
$PN"2"51;
"A"
$PN"1"23;
%"Q_RES"
"1","(-2725,5100)","0","pure_quanta","I165";
;
MATERIAL"CHIP"
VALUE"0"
TOLERANCE"5%"
WATTAGE"1/16W"
PACK_TYPE"0402LF"
PART_NUMBER"CS00002JB13"
CDS_LIB"pure_quanta"
LOCATION"R272"
$SEC"1"
CDS_SEC"1";
"B"
$PN"2"22;
"A"
$PN"1"54;
%"Q_RES"
"1","(-2725,5050)","0","pure_quanta","I166";
;
MATERIAL"CHIP"
VALUE"0"
CDS_LIB"pure_quanta"
PART_NUMBER"CS00002JB13"
PACK_TYPE"0402LF"
WATTAGE"1/16W"
TOLERANCE"5%"
LOCATION"R303"
$SEC"1"
CDS_SEC"1";
"B"
$PN"2"21;
"A"
$PN"1"56;
%"Q_RES"
"1","(-2550,4500)","0","pure_quanta","I167";
;
MATERIAL"CHIP"
VALUE"0"
CDS_LIB"pure_quanta"
TOLERANCE"5%"
WATTAGE"1/16W"
PACK_TYPE"0402LF"
PART_NUMBER"CS00002JB13"
LOCATION"R397"
$SEC"1"
CDS_SEC"1";
"B"
$PN"2"52;
"A"
$PN"1"50;
%"Q_RES"
"1","(-2550,4350)","0","pure_quanta","I168";
;
VALUE"0"
MATERIAL"CHIP"
CDS_LIB"pure_quanta"
TOLERANCE"5%"
WATTAGE"1/16W"
PACK_TYPE"0402LF"
PART_NUMBER"CS00002JB13"
LOCATION"R447"
$SEC"1"
CDS_SEC"1";
"B"
$PN"2"53;
"A"
$PN"1"18;
%"Q_RES"
"2","(-8750,6150)","2","pure_quanta","I17";
;
MATERIAL"CHIP"
TOLERANCE"1%"
VALUE"4.7K"
PACK_TYPE"0402LF"
WATTAGE"1/16W"
CDS_LIB"pure_quanta"
PART_NUMBER"CS24702FB06"
LOCATION"R625"
$SEC"1"
CDS_SEC"1";
"A"
$PN"1"9;
"B"
$PN"2"75;
%"VCCAUX15"
"1","(-8750,6350)","0","logical_power","I18";
;
HDL_POWER"P3V3_AUX"
CDS_LIB"logical_power";
"A"9;
%"Q_RES"
"1","(-7050,3500)","0","pure_quanta","I35";
;
MATERIAL"CHIP"
VALUE"0"
PART_NUMBER"CS00002JB13"
CDS_LIB"pure_quanta"
TOLERANCE"5%"
WATTAGE"1/16W"
PACK_TYPE"0402LF"
LOCATION"R571"
$SEC"1"
CDS_SEC"1";
"B"
$PN"2"36;
"A"
$PN"1"79;
%"Q_RES"
"1","(-7000,4750)","0","pure_quanta","I37";
;
VALUE"0"
MATERIAL"CHIP"
CDS_LIB"pure_quanta"
PART_NUMBER"CS00002JB13"
TOLERANCE"5%"
WATTAGE"1/16W"
PACK_TYPE"0402LF"
LOCATION"R634"
$SEC"1"
CDS_SEC"1";
"B"
$PN"2"24;
"A"
$PN"1"71;
END.
